(kicad_pcb
	(version 20260206)
	(generator "pcbnew")
	(generator_version "10.0")
	(general
		(thickness 1.6)
		(legacy_teardrops no)
	)
	(paper "A4")
	(title_block
		(title "Wiwynn_Tioga_Pass_MB.brd")
		(comment 1 "Tioga Pass / footprints 257-263 of 4770")
	)
	(layers
		(0 "F.Cu" signal "TOP")
		(4 "In1.Cu" signal "L2GND")
		(6 "In2.Cu" signal "L3")
		(8 "In3.Cu" signal "L4GND")
		(10 "In4.Cu" signal "L5")
		(12 "In5.Cu" signal "L6GND")
		(14 "In6.Cu" signal "L7VCC")
		(16 "In7.Cu" signal "L8VCC")
		(18 "In8.Cu" signal "L9GND")
		(20 "In9.Cu" signal "L10")
		(22 "In10.Cu" signal "L11GND")
		(24 "In11.Cu" signal "L12")
		(26 "In12.Cu" signal "L13GND")
		(2 "B.Cu" signal "BOTTOM")
		(9 "F.Adhes" user "F.Adhesive")
		(11 "B.Adhes" user "B.Adhesive")
		(13 "F.Paste" user "Package Geometry/Pastemask Top")
		(15 "B.Paste" user "Package Geometry/Pastemask Bottom")
		(5 "F.SilkS" user "Ref Des/Silkscreen Top")
		(7 "B.SilkS" user "Ref Des/Silkscreen Bottom")
		(1 "F.Mask" user "Board Geometry/Soldermask Top")
		(3 "B.Mask" user "Board Geometry/Soldermask Bottom")
		(17 "Dwgs.User" user "User.Drawings")
		(19 "Cmts.User" user "User.Comments")
		(21 "Eco1.User" user "User.Eco1")
		(23 "Eco2.User" user "User.Eco2")
		(25 "Edge.Cuts" user "Board Geometry/Outline")
		(27 "Margin" user)
		(31 "F.CrtYd" user "Package Geometry/Place Bound Top")
		(29 "B.CrtYd" user "Package Geometry/Place Bound Bottom")
		(35 "F.Fab" user "Ref Des/Assembly Top")
		(33 "B.Fab" user "Ref Des/Assembly Bottom")
	)
	(footprint ""
		(layer "F.Cu")
		(at 204.6224 -69.342 -90)
		(property "Reference" "CT38"
			(at -0.8382 -0.67818 270)
			(unlocked yes)
			(layer "F.SilkS")
			(effects
				(font
					(size 0.4064 0.254)
					(thickness 0.1524)
				)
				(justify left)
			)
		)
		(property "Value" ""
			(at 0 0 270)
			(layer "F.Fab")
			(effects
				(font
					(size 1.27 1.27)
				)
			)
		)
		(duplicate_pad_numbers_are_jumpers no)
		(fp_poly
			(pts
				(xy 0.3048 -0.1016) (xy 0.3048 0.9906) (xy -0.3048 0.9906) (xy -0.3048 -0.1016)
			)
			(stroke
				(width 0)
				(type default)
			)
			(fill no)
			(layer "F.CrtYd")
		)
		(fp_line
			(start -0.3048 0.9906)
			(end 0.3048 0.9906)
			(stroke
				(width 0.1)
				(type default)
			)
			(layer "F.Fab")
		)
		(fp_line
			(start 0.3048 0.9906)
			(end 0.3048 -0.1016)
			(stroke
				(width 0.1)
				(type default)
			)
			(layer "F.Fab")
		)
		(fp_line
			(start -0.3048 -0.1016)
			(end -0.3048 0.9906)
			(stroke
				(width 0.1)
				(type default)
			)
			(layer "F.Fab")
		)
		(fp_line
			(start 0.3048 -0.1016)
			(end -0.3048 -0.1016)
			(stroke
				(width 0.1)
				(type default)
			)
			(layer "F.Fab")
		)
		(pad "1" smd rect
			(at 0 0 270)
			(size 0.508 0.508)
			(layers "F.Cu" "F.Mask" "F.Paste")
			(net "VR_PVCCIN_CPU0_PHASE3")
		)
		(pad "2" smd rect
			(at 0 0.889 270)
			(size 0.508 0.508)
			(layers "F.Cu" "F.Mask" "F.Paste")
			(net "VR_PVCCIN_CPU0_PHASE3_RC")
		)
		(zone
			(layer "F.Cu")
			(hatch none 0.5)
			(connect_pads
				(clearance 0)
			)
			(min_thickness 0.25)
			(keepout
				(tracks not_allowed)
				(vias allowed)
				(pads allowed)
				(copperpour not_allowed)
				(footprints allowed)
			)
			(placement
				(enabled no)
				(sheetname "")
			)
			(fill
				(thermal_gap 0.5)
				(thermal_bridge_width 0.5)
				(island_removal_mode 0)
			)
			(polygon
				(pts
					(xy 203.9874 -69.596) (xy 203.9874 -69.088) (xy 204.3684 -69.088) (xy 204.3684 -69.596)
				)
			)
		)
		(zone
			(layer "F.Cu")
			(hatch none 0.5)
			(connect_pads
				(clearance 0)
			)
			(min_thickness 0.25)
			(keepout
				(tracks allowed)
				(vias not_allowed)
				(pads allowed)
				(copperpour not_allowed)
				(footprints allowed)
			)
			(placement
				(enabled no)
				(sheetname "")
			)
			(fill
				(thermal_gap 0.5)
				(thermal_bridge_width 0.5)
				(island_removal_mode 0)
			)
			(polygon
				(pts
					(xy 204.3684 -69.596) (xy 204.3684 -69.088) (xy 203.9874 -69.088) (xy 203.9874 -69.596)
				)
			)
		)
	)
	(footprint ""
		(layer "F.Cu")
		(at 40.60825 -103.491284 90)
		(property "Reference" "R1C5"
			(at 0 0 90)
			(layer "F.SilkS")
			(hide yes)
			(effects
				(font
					(size 1.27 1.27)
				)
			)
		)
		(property "Value" ""
			(at 0 0 90)
			(layer "F.Fab")
			(effects
				(font
					(size 1.27 1.27)
				)
			)
		)
		(duplicate_pad_numbers_are_jumpers no)
		(fp_poly
			(pts
				(xy -0.2794 -0.1016) (xy 0.2794 -0.1016) (xy 0.2794 0.9906) (xy -0.2794 0.9906)
			)
			(stroke
				(width 0)
				(type default)
			)
			(fill no)
			(layer "F.CrtYd")
		)
		(fp_line
			(start 0.2794 -0.1016)
			(end -0.2794 -0.1016)
			(stroke
				(width 0.1)
				(type default)
			)
			(layer "F.Fab")
		)
		(fp_line
			(start -0.2794 -0.1016)
			(end -0.2794 0.9906)
			(stroke
				(width 0.1)
				(type default)
			)
			(layer "F.Fab")
		)
		(fp_line
			(start 0.2794 0.9906)
			(end 0.2794 -0.1016)
			(stroke
				(width 0.1)
				(type default)
			)
			(layer "F.Fab")
		)
		(fp_line
			(start -0.2794 0.9906)
			(end 0.2794 0.9906)
			(stroke
				(width 0.1)
				(type default)
			)
			(layer "F.Fab")
		)
		(pad "1" smd rect
			(at 0 0 90)
			(size 0.508 0.508)
			(layers "F.Cu" "F.Mask" "F.Paste")
			(net "VSENSE_PVSA_CPU1_N")
		)
		(pad "2" smd rect
			(at 0 0.889 90)
			(size 0.508 0.508)
			(layers "F.Cu" "F.Mask" "F.Paste")
			(net "VSENSE_PVSA_CPU1_SKT_VRTN")
		)
		(zone
			(layer "F.Cu")
			(hatch none 0.5)
			(connect_pads
				(clearance 0)
			)
			(min_thickness 0.25)
			(keepout
				(tracks allowed)
				(vias not_allowed)
				(pads allowed)
				(copperpour not_allowed)
				(footprints allowed)
			)
			(placement
				(enabled no)
				(sheetname "")
			)
			(fill
				(thermal_gap 0.5)
				(thermal_bridge_width 0.5)
				(island_removal_mode 0)
			)
			(polygon
				(pts
					(xy 40.86225 -103.237284) (xy 40.86225 -103.745284) (xy 41.24325 -103.745284) (xy 41.24325 -103.237284)
				)
			)
		)
		(zone
			(layer "F.Cu")
			(hatch none 0.5)
			(connect_pads
				(clearance 0)
			)
			(min_thickness 0.25)
			(keepout
				(tracks not_allowed)
				(vias allowed)
				(pads allowed)
				(copperpour not_allowed)
				(footprints allowed)
			)
			(placement
				(enabled no)
				(sheetname "")
			)
			(fill
				(thermal_gap 0.5)
				(thermal_bridge_width 0.5)
				(island_removal_mode 0)
			)
			(polygon
				(pts
					(xy 41.24325 -103.237284) (xy 41.24325 -103.745284) (xy 40.86225 -103.745284) (xy 40.86225 -103.237284)
				)
			)
		)
	)
	(footprint ""
		(layer "F.Cu")
		(at 34.417 13.2715 -90)
		(property "Reference" "T1P36"
			(at 0 0 270)
			(layer "F.SilkS")
			(hide yes)
			(effects
				(font
					(size 1.27 1.27)
				)
			)
		)
		(property "Value" "*"
			(at 0 -3.44805 270)
			(unlocked yes)
			(layer "F.Fab")
			(hide yes)
			(effects
				(font
					(size 0.889 0.889)
					(thickness 0.1524)
				)
			)
		)
		(property "Device Type" "TPAD-SE-2P-GP_DISCRET-GA1-TPADA"
			(at 0 -4.97205 270)
			(unlocked yes)
			(layer "F.Fab")
			(hide yes)
			(effects
				(font
					(size 0.889 0.889)
					(thickness 0.1524)
				)
			)
		)
		(duplicate_pad_numbers_are_jumpers no)
		(fp_line
			(start -1.016 2.286)
			(end -1.016 -2.286)
			(stroke
				(width 0.1524)
				(type default)
			)
			(layer "F.SilkS")
		)
		(fp_line
			(start 1.016 2.286)
			(end -1.016 2.286)
			(stroke
				(width 0.1524)
				(type default)
			)
			(layer "F.SilkS")
		)
		(fp_line
			(start -1.016 -2.286)
			(end 1.016 -2.286)
			(stroke
				(width 0.1524)
				(type default)
			)
			(layer "F.SilkS")
		)
		(fp_line
			(start 1.016 -2.286)
			(end 1.016 2.286)
			(stroke
				(width 0.1524)
				(type default)
			)
			(layer "F.SilkS")
		)
		(fp_rect
			(start -1.27 2.54)
			(end 1.27 -2.54)
			(stroke
				(width 0)
				(type default)
			)
			(fill no)
			(layer "F.CrtYd")
		)
		(fp_rect
			(start -1.27 2.54)
			(end 1.27 -2.54)
			(stroke
				(width 0)
				(type default)
			)
			(fill no)
			(layer "F.Fab")
		)
		(pad "1" thru_hole circle
			(at 0 -1.27 270)
			(size 1.524 1.524)
			(drill 0.9144)
			(layers "*.Cu" "*.Mask")
			(remove_unused_layers no)
			(net "L14_50OHM_6INCH")
			(clearance -0.0508)
			(thermal_gap 0.127)
			(padstack
				(mode front_inner_back)
				(layer "Inner"
					(shape circle)
					(size 1.1684 1.1684)
					(clearance 0.127)
				)
				(layer "B.Cu"
					(shape circle)
					(size 1.524 1.524)
					(clearance -0.0508)
				)
			)
		)
		(pad "GND1" thru_hole rect
			(at 0 1.27 270)
			(size 1.524 1.524)
			(drill 0.9144)
			(layers "*.Cu" "*.Mask")
			(remove_unused_layers no)
			(net "GND")
			(clearance -0.0508)
			(thermal_gap 0.127)
			(padstack
				(mode front_inner_back)
				(layer "Inner"
					(shape circle)
					(size 1.1684 1.1684)
					(clearance 0.127)
				)
				(layer "B.Cu"
					(shape rect)
					(size 1.524 1.524)
					(clearance -0.0508)
				)
			)
		)
	)
	(footprint ""
		(layer "F.Cu")
		(at 116.2812 -74.5998 90)
		(property "Reference" "R3D31"
			(at 0 0 90)
			(layer "F.SilkS")
			(hide yes)
			(effects
				(font
					(size 1.27 1.27)
				)
			)
		)
		(property "Value" ""
			(at 0 0 90)
			(layer "F.Fab")
			(effects
				(font
					(size 1.27 1.27)
				)
			)
		)
		(duplicate_pad_numbers_are_jumpers no)
		(fp_poly
			(pts
				(xy -0.2794 -0.1016) (xy 0.2794 -0.1016) (xy 0.2794 0.9906) (xy -0.2794 0.9906)
			)
			(stroke
				(width 0)
				(type default)
			)
			(fill no)
			(layer "F.CrtYd")
		)
		(fp_line
			(start 0.2794 -0.1016)
			(end -0.2794 -0.1016)
			(stroke
				(width 0.1)
				(type default)
			)
			(layer "F.Fab")
		)
		(fp_line
			(start -0.2794 -0.1016)
			(end -0.2794 0.9906)
			(stroke
				(width 0.1)
				(type default)
			)
			(layer "F.Fab")
		)
		(fp_line
			(start 0.2794 0.9906)
			(end 0.2794 -0.1016)
			(stroke
				(width 0.1)
				(type default)
			)
			(layer "F.Fab")
		)
		(fp_line
			(start -0.2794 0.9906)
			(end 0.2794 0.9906)
			(stroke
				(width 0.1)
				(type default)
			)
			(layer "F.Fab")
		)
		(pad "1" smd rect
			(at 0 0 90)
			(size 0.508 0.508)
			(layers "F.Cu" "F.Mask" "F.Paste")
			(net "FM_CPU_BMC_INIT")
		)
		(pad "2" smd rect
			(at 0 0.889 90)
			(size 0.508 0.508)
			(layers "F.Cu" "F.Mask" "F.Paste")
			(net "H_CPU1_BMCINIT")
		)
		(zone
			(layer "F.Cu")
			(hatch none 0.5)
			(connect_pads
				(clearance 0)
			)
			(min_thickness 0.25)
			(keepout
				(tracks allowed)
				(vias not_allowed)
				(pads allowed)
				(copperpour not_allowed)
				(footprints allowed)
			)
			(placement
				(enabled no)
				(sheetname "")
			)
			(fill
				(thermal_gap 0.5)
				(thermal_bridge_width 0.5)
				(island_removal_mode 0)
			)
			(polygon
				(pts
					(xy 116.5352 -74.3458) (xy 116.5352 -74.8538) (xy 116.9162 -74.8538) (xy 116.9162 -74.3458)
				)
			)
		)
		(zone
			(layer "F.Cu")
			(hatch none 0.5)
			(connect_pads
				(clearance 0)
			)
			(min_thickness 0.25)
			(keepout
				(tracks not_allowed)
				(vias allowed)
				(pads allowed)
				(copperpour not_allowed)
				(footprints allowed)
			)
			(placement
				(enabled no)
				(sheetname "")
			)
			(fill
				(thermal_gap 0.5)
				(thermal_bridge_width 0.5)
				(island_removal_mode 0)
			)
			(polygon
				(pts
					(xy 116.9162 -74.3458) (xy 116.9162 -74.8538) (xy 116.5352 -74.8538) (xy 116.5352 -74.3458)
				)
			)
		)
	)
	(footprint ""
		(layer "F.Cu")
		(at 281.178 -72.263 90)
		(property "Reference" "R6D10"
			(at 0 0 90)
			(layer "F.SilkS")
			(hide yes)
			(effects
				(font
					(size 1.27 1.27)
				)
			)
		)
		(property "Value" ""
			(at 0 0 90)
			(layer "F.Fab")
			(effects
				(font
					(size 1.27 1.27)
				)
			)
		)
		(duplicate_pad_numbers_are_jumpers no)
		(fp_rect
			(start -0.2794 -0.1016)
			(end 0.2794 0.9906)
			(stroke
				(width 0)
				(type default)
			)
			(fill no)
			(layer "F.CrtYd")
		)
		(fp_line
			(start 0.2794 -0.1016)
			(end -0.2794 -0.1016)
			(stroke
				(width 0.1)
				(type default)
			)
			(layer "F.Fab")
		)
		(fp_line
			(start -0.2794 -0.1016)
			(end -0.2794 0.9906)
			(stroke
				(width 0.1)
				(type default)
			)
			(layer "F.Fab")
		)
		(fp_line
			(start 0.2794 0.9906)
			(end 0.2794 -0.1016)
			(stroke
				(width 0.1)
				(type default)
			)
			(layer "F.Fab")
		)
		(fp_line
			(start -0.2794 0.9906)
			(end 0.2794 0.9906)
			(stroke
				(width 0.1)
				(type default)
			)
			(layer "F.Fab")
		)
		(pad "1" smd rect
			(at 0 0 90)
			(size 0.508 0.508)
			(layers "F.Cu" "F.Mask" "F.Paste")
			(net "PVCCIO_CPU0")
		)
		(pad "2" smd rect
			(at 0 0.889 90)
			(size 0.508 0.508)
			(layers "F.Cu" "F.Mask" "F.Paste")
			(net "PU_CPU0_SOCKET_ID_1")
		)
		(zone
			(layer "F.Cu")
			(hatch none 0.5)
			(connect_pads
				(clearance 0)
			)
			(min_thickness 0.25)
			(keepout
				(tracks not_allowed)
				(vias allowed)
				(pads allowed)
				(copperpour not_allowed)
				(footprints allowed)
			)
			(placement
				(enabled no)
				(sheetname "")
			)
			(fill
				(thermal_gap 0.5)
				(thermal_bridge_width 0.5)
				(island_removal_mode 0)
			)
			(polygon
				(pts
					(xy 281.432 -72.009) (xy 281.813 -72.009) (xy 281.813 -72.517) (xy 281.432 -72.517)
				)
			)
		)
		(zone
			(layer "F.Cu")
			(hatch none 0.5)
			(connect_pads
				(clearance 0)
			)
			(min_thickness 0.25)
			(keepout
				(tracks allowed)
				(vias not_allowed)
				(pads allowed)
				(copperpour not_allowed)
				(footprints allowed)
			)
			(placement
				(enabled no)
				(sheetname "")
			)
			(fill
				(thermal_gap 0.5)
				(thermal_bridge_width 0.5)
				(island_removal_mode 0)
			)
			(polygon
				(pts
					(xy 281.432 -72.009) (xy 281.813 -72.009) (xy 281.813 -72.517) (xy 281.432 -72.517)
				)
			)
		)
	)
	(footprint ""
		(layer "F.Cu")
		(at 340.872064 -5.746496 180)
		(property "Reference" "L7G1"
			(at 3.378708 -4.251706 180)
			(unlocked yes)
			(layer "F.SilkS")
			(effects
				(font
					(size 0.4064 0.254)
					(thickness 0.1524)
				)
			)
		)
		(property "Value" ""
			(at 0 0 180)
			(layer "F.Fab")
			(effects
				(font
					(size 1.27 1.27)
				)
			)
		)
		(duplicate_pad_numbers_are_jumpers no)
		(fp_line
			(start 8.3693 3.199892)
			(end -1.1303 3.199892)
			(stroke
				(width 0.1524)
				(type default)
			)
			(layer "F.SilkS")
		)
		(fp_line
			(start 8.3693 1.6637)
			(end 8.3693 3.199892)
			(stroke
				(width 0.1524)
				(type default)
			)
			(layer "F.SilkS")
		)
		(fp_line
			(start 8.3693 -3.199892)
			(end 8.3693 -1.6637)
			(stroke
				(width 0.1524)
				(type default)
			)
			(layer "F.SilkS")
		)
		(fp_line
			(start -1.1303 3.199892)
			(end -1.1303 1.6637)
			(stroke
				(width 0.1524)
				(type default)
			)
			(layer "F.SilkS")
		)
		(fp_line
			(start -1.1303 -1.6637)
			(end -1.1303 -3.199892)
			(stroke
				(width 0.1524)
				(type default)
			)
			(layer "F.SilkS")
		)
		(fp_line
			(start -1.1303 -3.199892)
			(end 8.3693 -3.199892)
			(stroke
				(width 0.1524)
				(type default)
			)
			(layer "F.SilkS")
		)
		(fp_rect
			(start -1.1303 3.199892)
			(end 8.3693 -3.199892)
			(stroke
				(width 0)
				(type default)
			)
			(fill no)
			(layer "F.CrtYd")
		)
		(fp_line
			(start 8.3693 3.199892)
			(end -1.1303 3.199892)
			(stroke
				(width 0.1)
				(type default)
			)
			(layer "F.Fab")
		)
		(fp_line
			(start 8.3693 -3.199892)
			(end 8.3693 3.199892)
			(stroke
				(width 0.1)
				(type default)
			)
			(layer "F.Fab")
		)
		(fp_line
			(start -1.1303 3.199892)
			(end -1.1303 -3.199892)
			(stroke
				(width 0.1)
				(type default)
			)
			(layer "F.Fab")
		)
		(fp_line
			(start -1.1303 -3.199892)
			(end 8.3693 -3.199892)
			(stroke
				(width 0.1)
				(type default)
			)
			(layer "F.Fab")
		)
		(pad "1" smd rect
			(at 0 0 180)
			(size 3.683 2.667)
			(layers "F.Cu" "F.Mask" "F.Paste")
			(net "VR_PVDDQ_ABC_PH1_SW")
		)
		(pad "2" smd rect
			(at 7.239 0 180)
			(size 3.683 2.667)
			(layers "F.Cu" "F.Mask" "F.Paste")
			(net "PVDDQ_ABC")
		)
	)
	(footprint ""
		(layer "F.Cu")
		(at 489.204 -137.16 90)
		(property "Reference" "Q9A3"
			(at -0.88265 0.0254 0)
			(unlocked yes)
			(layer "F.SilkS")
			(effects
				(font
					(size 0.7874 0.5842)
					(thickness 0.1524)
				)
				(justify left)
			)
		)
		(property "Value" ""
			(at 0 0 90)
			(layer "F.Fab")
			(effects
				(font
					(size 1.27 1.27)
				)
			)
		)
		(duplicate_pad_numbers_are_jumpers no)
		(fp_line
			(start 1.778 -0.5715)
			(end 1.778 0.3175)
			(stroke
				(width 0.1524)
				(type default)
			)
			(layer "F.SilkS")
		)
		(fp_line
			(start 0.9525 -0.5715)
			(end 1.778 -0.5715)
			(stroke
				(width 0.1524)
				(type default)
			)
			(layer "F.SilkS")
		)
		(fp_line
			(start 0.381 0.635)
			(end 0.381 1.27)
			(stroke
				(width 0.1524)
				(type default)
			)
			(layer "F.SilkS")
		)
		(fp_line
			(start 1.778 2.4765)
			(end 1.778 1.5875)
			(stroke
				(width 0.1524)
				(type default)
			)
			(layer "F.SilkS")
		)
		(fp_line
			(start 0.9525 2.4765)
			(end 1.778 2.4765)
			(stroke
				(width 0.1524)
				(type default)
			)
			(layer "F.SilkS")
		)
		(fp_circle
			(center -0.9525 -0.9271)
			(end -0.9525 -0.8001)
			(stroke
				(width 0.254)
				(type default)
			)
			(fill no)
			(layer "F.SilkS")
		)
		(fp_poly
			(pts
				(xy 1.778 2.4765) (xy 0.381 2.4765) (xy 0.381 -0.5715) (xy 1.778 -0.5715)
			)
			(stroke
				(width 0)
				(type default)
			)
			(fill no)
			(layer "F.CrtYd")
		)
		(fp_line
			(start 1.778 -0.5715)
			(end 0.381 -0.5715)
			(stroke
				(width 0.1)
				(type default)
			)
			(layer "F.Fab")
		)
		(fp_line
			(start 0.381 -0.5715)
			(end 0.381 2.4765)
			(stroke
				(width 0.1)
				(type default)
			)
			(layer "F.Fab")
		)
		(fp_line
			(start 1.778 2.4765)
			(end 1.778 -0.5715)
			(stroke
				(width 0.1)
				(type default)
			)
			(layer "F.Fab")
		)
		(fp_line
			(start 0.381 2.4765)
			(end 1.778 2.4765)
			(stroke
				(width 0.1)
				(type default)
			)
			(layer "F.Fab")
		)
		(fp_circle
			(center -0.9525 -0.9271)
			(end -0.9525 -0.8001)
			(stroke
				(width 0.254)
				(type default)
			)
			(fill no)
			(layer "F.Fab")
		)
		(pad "1" smd rect
			(at 0 0 90)
			(size 1.143 0.508)
			(layers "F.Cu" "F.Mask" "F.Paste")
			(net "FM_BIOS_TOP_SWAP_SPKR")
		)
		(pad "2" smd rect
			(at 0 1.905 90)
			(size 1.143 0.508)
			(layers "F.Cu" "F.Mask" "F.Paste")
			(net "GND")
		)
		(pad "3" smd rect
			(at 2.159 0.9525 90)
			(size 1.143 0.508)
			(layers "F.Cu" "F.Mask" "F.Paste")
			(net "FM_SPEAKER_PCH_N")
		)
	)
)
